(kicad_pcb
	(version 20260206)
	(generator "pcbnew")
	(generator_version "10.0")
	(general
		(thickness 1.6)
		(legacy_teardrops no)
	)
	(paper "A4")
	(title_block
		(title "01162023_DA0F0TEBIF0_F0T_Expander_BD_F_brd_V02_OCP.brd")
		(comment 1 "Grand Teton / footprints 780-787 of 9728")
	)
	(layers
		(0 "F.Cu" signal "TOP")
		(4 "In1.Cu" signal "GND")
		(6 "In2.Cu" signal "VCC")
		(8 "In3.Cu" signal "VCC1")
		(10 "In4.Cu" signal "GND1")
		(12 "In5.Cu" signal "IN1")
		(14 "In6.Cu" signal "GND2")
		(16 "In7.Cu" signal "IN2")
		(18 "In8.Cu" signal "GND3")
		(20 "In9.Cu" signal "IN3")
		(22 "In10.Cu" signal "GND4")
		(24 "In11.Cu" signal "IN4")
		(26 "In12.Cu" signal "GND5")
		(28 "In13.Cu" signal "IN5")
		(30 "In14.Cu" signal "GND6")
		(32 "In15.Cu" signal "IN6")
		(34 "In16.Cu" signal "GND7")
		(2 "B.Cu" signal "BOTTOM")
		(9 "F.Adhes" user "F.Adhesive")
		(11 "B.Adhes" user "B.Adhesive")
		(13 "F.Paste" user "Package Geometry/Pastemask Top")
		(15 "B.Paste" user "Package Geometry/Pastemask Bottom")
		(5 "F.SilkS" user "Ref Des/Silkscreen Top")
		(7 "B.SilkS" user "Ref Des/Silkscreen Bottom")
		(1 "F.Mask" user "Board Geometry/Soldermask Top")
		(3 "B.Mask" user "Board Geometry/Soldermask Bottom")
		(17 "Dwgs.User" user "User.Drawings")
		(19 "Cmts.User" user "User.Comments")
		(21 "Eco1.User" user "User.Eco1")
		(23 "Eco2.User" user "User.Eco2")
		(25 "Edge.Cuts" user "Board Geometry/Outline")
		(27 "Margin" user)
		(31 "F.CrtYd" user "Package Geometry/Place Bound Top")
		(29 "B.CrtYd" user "Package Geometry/Place Bound Bottom")
		(35 "F.Fab" user "Ref Des/Assembly Top")
		(33 "B.Fab" user "Ref Des/Assembly Bottom")
	)
	(footprint ""
		(layer "F.Cu")
		(at 312.541666 -27.006296 -90)
		(property "Reference" "PR7122"
			(at 0 0 270)
			(layer "F.SilkS")
			(hide yes)
			(effects
				(font
					(size 1.27 1.27)
				)
			)
		)
		(property "Value" ""
			(at 0 0 270)
			(layer "F.Fab")
			(effects
				(font
					(size 1.27 1.27)
				)
			)
		)
		(duplicate_pad_numbers_are_jumpers no)
		(fp_line
			(start -0.7874 0.4064)
			(end -0.7874 -0.4064)
			(stroke
				(width 0.1524)
				(type default)
			)
			(layer "F.SilkS")
		)
		(fp_line
			(start 0.7874 0.4064)
			(end -0.7874 0.4064)
			(stroke
				(width 0.1524)
				(type default)
			)
			(layer "F.SilkS")
		)
		(fp_line
			(start -0.7874 -0.4064)
			(end 0.7874 -0.4064)
			(stroke
				(width 0.1524)
				(type default)
			)
			(layer "F.SilkS")
		)
		(fp_line
			(start 0.7874 -0.4064)
			(end 0.7874 0.4064)
			(stroke
				(width 0.1524)
				(type default)
			)
			(layer "F.SilkS")
		)
		(fp_line
			(start -0.67945 0.3048)
			(end -0.67945 -0.305054)
			(stroke
				(width 0.1)
				(type default)
			)
			(layer "F.Fab")
		)
		(fp_line
			(start -0.12065 0.3048)
			(end -0.67945 0.3048)
			(stroke
				(width 0.1)
				(type default)
			)
			(layer "F.Fab")
		)
		(fp_line
			(start 0.120396 0.3048)
			(end 0.120396 0.2794)
			(stroke
				(width 0.1)
				(type default)
			)
			(layer "F.Fab")
		)
		(fp_line
			(start 0.67945 0.3048)
			(end 0.120396 0.3048)
			(stroke
				(width 0.1)
				(type default)
			)
			(layer "F.Fab")
		)
		(fp_line
			(start -0.12065 0.2794)
			(end -0.12065 0.3048)
			(stroke
				(width 0.1)
				(type default)
			)
			(layer "F.Fab")
		)
		(fp_line
			(start 0.120396 0.2794)
			(end -0.12065 0.2794)
			(stroke
				(width 0.1)
				(type default)
			)
			(layer "F.Fab")
		)
		(fp_line
			(start -0.12065 -0.2794)
			(end 0.12065 -0.2794)
			(stroke
				(width 0.1)
				(type default)
			)
			(layer "F.Fab")
		)
		(fp_line
			(start 0.12065 -0.2794)
			(end 0.12065 -0.3048)
			(stroke
				(width 0.1)
				(type default)
			)
			(layer "F.Fab")
		)
		(fp_line
			(start 0.12065 -0.3048)
			(end 0.67945 -0.3048)
			(stroke
				(width 0.1)
				(type default)
			)
			(layer "F.Fab")
		)
		(fp_line
			(start 0.67945 -0.3048)
			(end 0.67945 0.3048)
			(stroke
				(width 0.1)
				(type default)
			)
			(layer "F.Fab")
		)
		(fp_line
			(start -0.67945 -0.305054)
			(end -0.12065 -0.305054)
			(stroke
				(width 0.1)
				(type default)
			)
			(layer "F.Fab")
		)
		(fp_line
			(start -0.12065 -0.305054)
			(end -0.12065 -0.2794)
			(stroke
				(width 0.1)
				(type default)
			)
			(layer "F.Fab")
		)
		(pad "1" smd circle
			(at -0.40005 0 270)
			(size 0 0)
			(layers "F.Cu" "F.Mask" "F.Paste")
			(net "P3V3_SSD11_CO_ILIMIT")
		)
		(pad "2" smd circle
			(at 0.40005 0 270)
			(size 0 0)
			(layers "F.Cu" "F.Mask" "F.Paste")
			(net "GND")
		)
	)
	(footprint ""
		(layer "F.Cu")
		(at 106.614214 -219.111576)
		(property "Reference" "PC287"
			(at 0 0 0)
			(layer "F.SilkS")
			(hide yes)
			(effects
				(font
					(size 1.27 1.27)
				)
			)
		)
		(property "Value" ""
			(at 0 0 0)
			(layer "F.Fab")
			(effects
				(font
					(size 1.27 1.27)
				)
			)
		)
		(duplicate_pad_numbers_are_jumpers no)
		(fp_line
			(start -1.524 -0.762)
			(end 1.524 -0.762)
			(stroke
				(width 0.1524)
				(type default)
			)
			(layer "F.SilkS")
		)
		(fp_line
			(start -1.524 0.762)
			(end -1.524 -0.762)
			(stroke
				(width 0.1524)
				(type default)
			)
			(layer "F.SilkS")
		)
		(fp_line
			(start 1.524 -0.762)
			(end 1.524 0.762)
			(stroke
				(width 0.1524)
				(type default)
			)
			(layer "F.SilkS")
		)
		(fp_line
			(start 1.524 0.762)
			(end -1.524 0.762)
			(stroke
				(width 0.1524)
				(type default)
			)
			(layer "F.SilkS")
		)
		(fp_line
			(start -1.1049 -0.724916)
			(end -1.1049 0.724916)
			(stroke
				(width 0.1)
				(type default)
			)
			(layer "F.Fab")
		)
		(fp_line
			(start -1.1049 0.724916)
			(end 1.1049 0.724916)
			(stroke
				(width 0.1)
				(type default)
			)
			(layer "F.Fab")
		)
		(fp_line
			(start 1.1049 -0.724916)
			(end -1.1049 -0.724916)
			(stroke
				(width 0.1)
				(type default)
			)
			(layer "F.Fab")
		)
		(fp_line
			(start 1.1049 0.724916)
			(end 1.1049 -0.724916)
			(stroke
				(width 0.1)
				(type default)
			)
			(layer "F.Fab")
		)
		(pad "1" smd rect
			(at -0.889 0 180)
			(size 1.016 1.27)
			(layers "F.Cu" "F.Mask" "F.Paste")
			(net "SW_P12V_P1V8_PEX_FLT")
		)
		(pad "2" smd rect
			(at 0.889 0 180)
			(size 1.016 1.27)
			(layers "F.Cu" "F.Mask" "F.Paste")
			(net "GND")
		)
	)
	(footprint ""
		(layer "F.Cu")
		(at 235.707936 -257.975862 -90)
		(property "Reference" "R6521"
			(at 0 0 270)
			(layer "F.SilkS")
			(hide yes)
			(effects
				(font
					(size 1.27 1.27)
				)
			)
		)
		(property "Value" ""
			(at 0 0 270)
			(layer "F.Fab")
			(effects
				(font
					(size 1.27 1.27)
				)
			)
		)
		(duplicate_pad_numbers_are_jumpers no)
		(fp_line
			(start -0.7874 0.4064)
			(end -0.7874 -0.4064)
			(stroke
				(width 0.1524)
				(type default)
			)
			(layer "F.SilkS")
		)
		(fp_line
			(start 0.7874 0.4064)
			(end -0.7874 0.4064)
			(stroke
				(width 0.1524)
				(type default)
			)
			(layer "F.SilkS")
		)
		(fp_line
			(start -0.7874 -0.4064)
			(end 0.7874 -0.4064)
			(stroke
				(width 0.1524)
				(type default)
			)
			(layer "F.SilkS")
		)
		(fp_line
			(start 0.7874 -0.4064)
			(end 0.7874 0.4064)
			(stroke
				(width 0.1524)
				(type default)
			)
			(layer "F.SilkS")
		)
		(fp_line
			(start -0.67945 0.3048)
			(end -0.67945 -0.305054)
			(stroke
				(width 0.1)
				(type default)
			)
			(layer "F.Fab")
		)
		(fp_line
			(start -0.12065 0.3048)
			(end -0.67945 0.3048)
			(stroke
				(width 0.1)
				(type default)
			)
			(layer "F.Fab")
		)
		(fp_line
			(start 0.120396 0.3048)
			(end 0.120396 0.2794)
			(stroke
				(width 0.1)
				(type default)
			)
			(layer "F.Fab")
		)
		(fp_line
			(start 0.67945 0.3048)
			(end 0.120396 0.3048)
			(stroke
				(width 0.1)
				(type default)
			)
			(layer "F.Fab")
		)
		(fp_line
			(start -0.12065 0.2794)
			(end -0.12065 0.3048)
			(stroke
				(width 0.1)
				(type default)
			)
			(layer "F.Fab")
		)
		(fp_line
			(start 0.120396 0.2794)
			(end -0.12065 0.2794)
			(stroke
				(width 0.1)
				(type default)
			)
			(layer "F.Fab")
		)
		(fp_line
			(start -0.12065 -0.2794)
			(end 0.12065 -0.2794)
			(stroke
				(width 0.1)
				(type default)
			)
			(layer "F.Fab")
		)
		(fp_line
			(start 0.12065 -0.2794)
			(end 0.12065 -0.3048)
			(stroke
				(width 0.1)
				(type default)
			)
			(layer "F.Fab")
		)
		(fp_line
			(start 0.12065 -0.3048)
			(end 0.67945 -0.3048)
			(stroke
				(width 0.1)
				(type default)
			)
			(layer "F.Fab")
		)
		(fp_line
			(start 0.67945 -0.3048)
			(end 0.67945 0.3048)
			(stroke
				(width 0.1)
				(type default)
			)
			(layer "F.Fab")
		)
		(fp_line
			(start -0.67945 -0.305054)
			(end -0.12065 -0.305054)
			(stroke
				(width 0.1)
				(type default)
			)
			(layer "F.Fab")
		)
		(fp_line
			(start -0.12065 -0.305054)
			(end -0.12065 -0.2794)
			(stroke
				(width 0.1)
				(type default)
			)
			(layer "F.Fab")
		)
		(pad "1" smd circle
			(at -0.40005 0 270)
			(size 0 0)
			(layers "F.Cu" "F.Mask" "F.Paste")
			(net "P1V25_SERDES_VDDPLL_PEX2")
		)
		(pad "2" smd circle
			(at 0.40005 0 270)
			(size 0 0)
			(layers "F.Cu" "F.Mask" "F.Paste")
			(net "P1V25_SERDES_VDDPLL_PEX2_C0")
		)
	)
	(footprint ""
		(layer "F.Cu")
		(at 268.838426 -104.695498)
		(property "Reference" "C479"
			(at 0 0 0)
			(layer "F.SilkS")
			(hide yes)
			(effects
				(font
					(size 1.27 1.27)
				)
			)
		)
		(property "Value" ""
			(at 0 0 0)
			(layer "F.Fab")
			(effects
				(font
					(size 1.27 1.27)
				)
			)
		)
		(duplicate_pad_numbers_are_jumpers no)
		(fp_line
			(start -0.299974 -0.150114)
			(end 0.299974 -0.150114)
			(stroke
				(width 0.1)
				(type default)
			)
			(layer "F.Fab")
		)
		(fp_line
			(start -0.299974 0.150114)
			(end -0.299974 -0.150114)
			(stroke
				(width 0.1)
				(type default)
			)
			(layer "F.Fab")
		)
		(fp_line
			(start 0.299974 -0.150114)
			(end 0.299974 0.150114)
			(stroke
				(width 0.1)
				(type default)
			)
			(layer "F.Fab")
		)
		(fp_line
			(start 0.299974 0.150114)
			(end -0.299974 0.150114)
			(stroke
				(width 0.1)
				(type default)
			)
			(layer "F.Fab")
		)
		(pad "1" smd rect
			(at -0.2667 0)
			(size 0.3048 0.381)
			(layers "F.Cu" "F.Mask" "F.Paste")
			(net "P5E_PEX2_STN1_TX_DN<19>")
		)
		(pad "2" smd rect
			(at 0.2667 0)
			(size 0.3048 0.381)
			(layers "F.Cu" "F.Mask" "F.Paste")
			(net "P5E_PEX2_STN1_TX_C_DN<19>")
		)
	)
	(footprint ""
		(layer "F.Cu")
		(at 32.657288 -356.244906 90)
		(property "Reference" "C2165"
			(at 0 0 90)
			(layer "F.SilkS")
			(hide yes)
			(effects
				(font
					(size 1.27 1.27)
				)
			)
		)
		(property "Value" ""
			(at 0 0 90)
			(layer "F.Fab")
			(effects
				(font
					(size 1.27 1.27)
				)
			)
		)
		(duplicate_pad_numbers_are_jumpers no)
		(fp_line
			(start 0.299974 -0.150114)
			(end 0.299974 0.150114)
			(stroke
				(width 0.1)
				(type default)
			)
			(layer "F.Fab")
		)
		(fp_line
			(start -0.299974 -0.150114)
			(end 0.299974 -0.150114)
			(stroke
				(width 0.1)
				(type default)
			)
			(layer "F.Fab")
		)
		(fp_line
			(start 0.299974 0.150114)
			(end -0.299974 0.150114)
			(stroke
				(width 0.1)
				(type default)
			)
			(layer "F.Fab")
		)
		(fp_line
			(start -0.299974 0.150114)
			(end -0.299974 -0.150114)
			(stroke
				(width 0.1)
				(type default)
			)
			(layer "F.Fab")
		)
		(pad "1" smd rect
			(at -0.2667 0 90)
			(size 0.3048 0.381)
			(layers "F.Cu" "F.Mask" "F.Paste")
			(net "P5E_PEX0_STN4_TX_DN<73>")
		)
		(pad "2" smd rect
			(at 0.2667 0 90)
			(size 0.3048 0.381)
			(layers "F.Cu" "F.Mask" "F.Paste")
			(net "P5E_PEX0_STN4_TX_C_DN<73>")
		)
	)
	(footprint ""
		(layer "F.Cu")
		(at 18.207736 -152.71115 90)
		(property "Reference" "R684"
			(at 0 0 90)
			(layer "F.SilkS")
			(hide yes)
			(effects
				(font
					(size 1.27 1.27)
				)
			)
		)
		(property "Value" ""
			(at 0 0 90)
			(layer "F.Fab")
			(effects
				(font
					(size 1.27 1.27)
				)
			)
		)
		(duplicate_pad_numbers_are_jumpers no)
		(fp_line
			(start 0.7874 -0.4064)
			(end 0.7874 0.4064)
			(stroke
				(width 0.1524)
				(type default)
			)
			(layer "F.SilkS")
		)
		(fp_line
			(start -0.7874 -0.4064)
			(end 0.7874 -0.4064)
			(stroke
				(width 0.1524)
				(type default)
			)
			(layer "F.SilkS")
		)
		(fp_line
			(start 0.7874 0.4064)
			(end -0.7874 0.4064)
			(stroke
				(width 0.1524)
				(type default)
			)
			(layer "F.SilkS")
		)
		(fp_line
			(start -0.7874 0.4064)
			(end -0.7874 -0.4064)
			(stroke
				(width 0.1524)
				(type default)
			)
			(layer "F.SilkS")
		)
		(fp_line
			(start -0.12065 -0.305054)
			(end -0.12065 -0.2794)
			(stroke
				(width 0.1)
				(type default)
			)
			(layer "F.Fab")
		)
		(fp_line
			(start -0.67945 -0.305054)
			(end -0.12065 -0.305054)
			(stroke
				(width 0.1)
				(type default)
			)
			(layer "F.Fab")
		)
		(fp_line
			(start 0.67945 -0.3048)
			(end 0.67945 0.3048)
			(stroke
				(width 0.1)
				(type default)
			)
			(layer "F.Fab")
		)
		(fp_line
			(start 0.12065 -0.3048)
			(end 0.67945 -0.3048)
			(stroke
				(width 0.1)
				(type default)
			)
			(layer "F.Fab")
		)
		(fp_line
			(start 0.12065 -0.2794)
			(end 0.12065 -0.3048)
			(stroke
				(width 0.1)
				(type default)
			)
			(layer "F.Fab")
		)
		(fp_line
			(start -0.12065 -0.2794)
			(end 0.12065 -0.2794)
			(stroke
				(width 0.1)
				(type default)
			)
			(layer "F.Fab")
		)
		(fp_line
			(start 0.120396 0.2794)
			(end -0.12065 0.2794)
			(stroke
				(width 0.1)
				(type default)
			)
			(layer "F.Fab")
		)
		(fp_line
			(start -0.12065 0.2794)
			(end -0.12065 0.3048)
			(stroke
				(width 0.1)
				(type default)
			)
			(layer "F.Fab")
		)
		(fp_line
			(start 0.67945 0.3048)
			(end 0.120396 0.3048)
			(stroke
				(width 0.1)
				(type default)
			)
			(layer "F.Fab")
		)
		(fp_line
			(start 0.120396 0.3048)
			(end 0.120396 0.2794)
			(stroke
				(width 0.1)
				(type default)
			)
			(layer "F.Fab")
		)
		(fp_line
			(start -0.12065 0.3048)
			(end -0.67945 0.3048)
			(stroke
				(width 0.1)
				(type default)
			)
			(layer "F.Fab")
		)
		(fp_line
			(start -0.67945 0.3048)
			(end -0.67945 -0.305054)
			(stroke
				(width 0.1)
				(type default)
			)
			(layer "F.Fab")
		)
		(pad "1" smd circle
			(at -0.40005 0 90)
			(size 0 0)
			(layers "F.Cu" "F.Mask" "F.Paste")
			(net "NIC0_ADC_ALERT_N")
		)
		(pad "2" smd circle
			(at 0.40005 0 90)
			(size 0 0)
			(layers "F.Cu" "F.Mask" "F.Paste")
			(net "NIC_ADC_ALERT_N")
		)
	)
	(footprint ""
		(layer "F.Cu")
		(at 131.007612 -154.510994)
		(property "Reference" "PC620"
			(at 0 0 0)
			(layer "F.SilkS")
			(hide yes)
			(effects
				(font
					(size 1.27 1.27)
				)
			)
		)
		(property "Value" ""
			(at 0 0 0)
			(layer "F.Fab")
			(effects
				(font
					(size 1.27 1.27)
				)
			)
		)
		(duplicate_pad_numbers_are_jumpers no)
		(fp_line
			(start -0.7874 -0.4064)
			(end 0.7874 -0.4064)
			(stroke
				(width 0.1524)
				(type default)
			)
			(layer "F.SilkS")
		)
		(fp_line
			(start -0.7874 0.4064)
			(end -0.7874 -0.4064)
			(stroke
				(width 0.1524)
				(type default)
			)
			(layer "F.SilkS")
		)
		(fp_line
			(start 0.7874 -0.4064)
			(end 0.7874 0.4064)
			(stroke
				(width 0.1524)
				(type default)
			)
			(layer "F.SilkS")
		)
		(fp_line
			(start 0.7874 0.4064)
			(end -0.7874 0.4064)
			(stroke
				(width 0.1524)
				(type default)
			)
			(layer "F.SilkS")
		)
		(fp_line
			(start -0.67945 -0.305054)
			(end -0.12065 -0.305054)
			(stroke
				(width 0.1)
				(type default)
			)
			(layer "F.Fab")
		)
		(fp_line
			(start -0.67945 0.3048)
			(end -0.67945 -0.305054)
			(stroke
				(width 0.1)
				(type default)
			)
			(layer "F.Fab")
		)
		(fp_line
			(start -0.12065 -0.305054)
			(end -0.12065 -0.2794)
			(stroke
				(width 0.1)
				(type default)
			)
			(layer "F.Fab")
		)
		(fp_line
			(start -0.12065 -0.2794)
			(end 0.12065 -0.2794)
			(stroke
				(width 0.1)
				(type default)
			)
			(layer "F.Fab")
		)
		(fp_line
			(start -0.12065 0.2794)
			(end -0.12065 0.3048)
			(stroke
				(width 0.1)
				(type default)
			)
			(layer "F.Fab")
		)
		(fp_line
			(start -0.12065 0.3048)
			(end -0.67945 0.3048)
			(stroke
				(width 0.1)
				(type default)
			)
			(layer "F.Fab")
		)
		(fp_line
			(start 0.120396 0.2794)
			(end -0.12065 0.2794)
			(stroke
				(width 0.1)
				(type default)
			)
			(layer "F.Fab")
		)
		(fp_line
			(start 0.120396 0.3048)
			(end 0.120396 0.2794)
			(stroke
				(width 0.1)
				(type default)
			)
			(layer "F.Fab")
		)
		(fp_line
			(start 0.12065 -0.3048)
			(end 0.67945 -0.3048)
			(stroke
				(width 0.1)
				(type default)
			)
			(layer "F.Fab")
		)
		(fp_line
			(start 0.12065 -0.2794)
			(end 0.12065 -0.3048)
			(stroke
				(width 0.1)
				(type default)
			)
			(layer "F.Fab")
		)
		(fp_line
			(start 0.67945 -0.3048)
			(end 0.67945 0.3048)
			(stroke
				(width 0.1)
				(type default)
			)
			(layer "F.Fab")
		)
		(fp_line
			(start 0.67945 0.3048)
			(end 0.120396 0.3048)
			(stroke
				(width 0.1)
				(type default)
			)
			(layer "F.Fab")
		)
		(pad "1" smd circle
			(at -0.40005 0)
			(size 0 0)
			(layers "F.Cu" "F.Mask" "F.Paste")
			(net "P12V_NIC2_R")
		)
		(pad "2" smd circle
			(at 0.40005 0)
			(size 0 0)
			(layers "F.Cu" "F.Mask" "F.Paste")
			(net "GND")
		)
	)
	(footprint ""
		(layer "F.Cu")
		(at 62.509908 -165.670484 -90)
		(property "Reference" "R2464"
			(at 0 0 270)
			(layer "F.SilkS")
			(hide yes)
			(effects
				(font
					(size 1.27 1.27)
				)
			)
		)
		(property "Value" ""
			(at 0 0 270)
			(layer "F.Fab")
			(effects
				(font
					(size 1.27 1.27)
				)
			)
		)
		(duplicate_pad_numbers_are_jumpers no)
		(fp_line
			(start -0.7874 0.4064)
			(end -0.7874 -0.4064)
			(stroke
				(width 0.1524)
				(type default)
			)
			(layer "F.SilkS")
		)
		(fp_line
			(start 0.7874 0.4064)
			(end -0.7874 0.4064)
			(stroke
				(width 0.1524)
				(type default)
			)
			(layer "F.SilkS")
		)
		(fp_line
			(start -0.7874 -0.4064)
			(end 0.7874 -0.4064)
			(stroke
				(width 0.1524)
				(type default)
			)
			(layer "F.SilkS")
		)
		(fp_line
			(start 0.7874 -0.4064)
			(end 0.7874 0.4064)
			(stroke
				(width 0.1524)
				(type default)
			)
			(layer "F.SilkS")
		)
		(fp_line
			(start -0.67945 0.3048)
			(end -0.67945 -0.305054)
			(stroke
				(width 0.1)
				(type default)
			)
			(layer "F.Fab")
		)
		(fp_line
			(start -0.12065 0.3048)
			(end -0.67945 0.3048)
			(stroke
				(width 0.1)
				(type default)
			)
			(layer "F.Fab")
		)
		(fp_line
			(start 0.120396 0.3048)
			(end 0.120396 0.2794)
			(stroke
				(width 0.1)
				(type default)
			)
			(layer "F.Fab")
		)
		(fp_line
			(start 0.67945 0.3048)
			(end 0.120396 0.3048)
			(stroke
				(width 0.1)
				(type default)
			)
			(layer "F.Fab")
		)
		(fp_line
			(start -0.12065 0.2794)
			(end -0.12065 0.3048)
			(stroke
				(width 0.1)
				(type default)
			)
			(layer "F.Fab")
		)
		(fp_line
			(start 0.120396 0.2794)
			(end -0.12065 0.2794)
			(stroke
				(width 0.1)
				(type default)
			)
			(layer "F.Fab")
		)
		(fp_line
			(start -0.12065 -0.2794)
			(end 0.12065 -0.2794)
			(stroke
				(width 0.1)
				(type default)
			)
			(layer "F.Fab")
		)
		(fp_line
			(start 0.12065 -0.2794)
			(end 0.12065 -0.3048)
			(stroke
				(width 0.1)
				(type default)
			)
			(layer "F.Fab")
		)
		(fp_line
			(start 0.12065 -0.3048)
			(end 0.67945 -0.3048)
			(stroke
				(width 0.1)
				(type default)
			)
			(layer "F.Fab")
		)
		(fp_line
			(start 0.67945 -0.3048)
			(end 0.67945 0.3048)
			(stroke
				(width 0.1)
				(type default)
			)
			(layer "F.Fab")
		)
		(fp_line
			(start -0.67945 -0.305054)
			(end -0.12065 -0.305054)
			(stroke
				(width 0.1)
				(type default)
			)
			(layer "F.Fab")
		)
		(fp_line
			(start -0.12065 -0.305054)
			(end -0.12065 -0.2794)
			(stroke
				(width 0.1)
				(type default)
			)
			(layer "F.Fab")
		)
		(pad "1" smd circle
			(at -0.40005 0 270)
			(size 0 0)
			(layers "F.Cu" "F.Mask" "F.Paste")
			(net "NIC0_PWRBRK_R_N")
		)
		(pad "2" smd circle
			(at 0.40005 0 270)
			(size 0 0)
			(layers "F.Cu" "F.Mask" "F.Paste")
			(net "NIC0_PWRBRK_N")
		)
	)
)
